(kicad_pcb
	(version 20260206)
	(generator "pcbnew")
	(generator_version "10.0")
	(general
		(thickness 1.6)
		(legacy_teardrops no)
	)
	(paper "A4")
	(title_block
		(title "Bryce Canyon_R.DPB_16317-1_OCP.brd")
		(comment 1 "Bryce Canyon / footprints 2093-2098 of 2099")
	)
	(layers
		(0 "F.Cu" signal "TOP")
		(4 "In1.Cu" signal "L2GND")
		(6 "In2.Cu" signal "L3")
		(8 "In3.Cu" signal "L4VCC")
		(10 "In4.Cu" signal "L5VCC")
		(12 "In5.Cu" signal "L6")
		(14 "In6.Cu" signal "L7GND")
		(2 "B.Cu" signal "BOTTOM")
		(9 "F.Adhes" user "F.Adhesive")
		(11 "B.Adhes" user "B.Adhesive")
		(13 "F.Paste" user "Package Geometry/Pastemask Top")
		(15 "B.Paste" user "Package Geometry/Pastemask Bottom")
		(5 "F.SilkS" user "Ref Des/Silkscreen Top")
		(7 "B.SilkS" user "Ref Des/Silkscreen Bottom")
		(1 "F.Mask" user "Board Geometry/Soldermask Top")
		(3 "B.Mask" user "Board Geometry/Soldermask Bottom")
		(17 "Dwgs.User" user "User.Drawings")
		(19 "Cmts.User" user "User.Comments")
		(21 "Eco1.User" user "User.Eco1")
		(23 "Eco2.User" user "User.Eco2")
		(25 "Edge.Cuts" user "Board Geometry/Outline")
		(27 "Margin" user)
		(31 "F.CrtYd" user "Package Geometry/Place Bound Top")
		(29 "B.CrtYd" user "Package Geometry/Place Bound Bottom")
		(35 "F.Fab" user "Ref Des/Assembly Top")
		(33 "B.Fab" user "Ref Des/Assembly Bottom")
	)
	(footprint ""
		(layer "B.Cu")
		(at 167.7162 -372.872 90)
		(property "Reference" "R996"
			(at 0 0 90)
			(layer "B.SilkS")
			(hide yes)
			(effects
				(font
					(size 1.27 1.27)
				)
				(justify mirror)
			)
		)
		(property "Value" "10R2F-L-GP"
			(at -0.064008 -3.993896 90)
			(unlocked yes)
			(layer "B.Fab")
			(hide yes)
			(effects
				(font
					(size 1.016 1.016)
					(thickness 0.1524)
				)
				(justify mirror)
			)
		)
		(property "Device Type" "R402H14"
			(at -0.064008 -5.517896 90)
			(unlocked yes)
			(layer "B.Fab")
			(hide yes)
			(effects
				(font
					(size 1.016 1.016)
					(thickness 0.1524)
				)
				(justify mirror)
			)
		)
		(duplicate_pad_numbers_are_jumpers no)
		(fp_line
			(start 0.508 -0.9398)
			(end 0.508 0.9398)
			(stroke
				(width 0.1524)
				(type default)
			)
			(layer "B.SilkS")
		)
		(fp_line
			(start -0.508 -0.9398)
			(end 0.508 -0.9398)
			(stroke
				(width 0.1524)
				(type default)
			)
			(layer "B.SilkS")
		)
		(fp_rect
			(start 0.508 0.9398)
			(end -0.508 -0.9398)
			(stroke
				(width 0)
				(type default)
			)
			(fill no)
			(layer "B.CrtYd")
		)
		(fp_rect
			(start 0.508 0.9398)
			(end -0.508 -0.9398)
			(stroke
				(width 0)
				(type default)
			)
			(fill no)
			(layer "B.Fab")
		)
		(pad "1" smd custom
			(at 0 -0.4445 270)
			(size 0.1397 0.1397)
			(layers "B.Cu" "B.Mask" "B.Paste")
			(net "MB0_CM_SENSE_R1_P")
			(options
				(clearance outline)
				(anchor circle)
			)
			(primitives
				(gr_poly
					(pts
						(arc
							(start -0.1778 0.2794)
							(mid -0.249642 0.249642)
							(end -0.2794 0.1778)
						)
						(arc
							(start -0.2794 -0.1778)
							(mid -0.249642 -0.249642)
							(end -0.1778 -0.2794)
						)
						(arc
							(start 0.1778 -0.2794)
							(mid 0.249642 -0.249642)
							(end 0.2794 -0.1778)
						)
						(arc
							(start 0.2794 0.1778)
							(mid 0.249642 0.249642)
							(end 0.1778 0.2794)
						)
					)
					(width 0)
					(fill yes)
				)
			)
		)
		(pad "2" smd custom
			(at 0 0.4445 270)
			(size 0.1397 0.1397)
			(layers "B.Cu" "B.Mask" "B.Paste")
			(net "MB0_CM_SENSE_P")
			(options
				(clearance outline)
				(anchor circle)
			)
			(primitives
				(gr_poly
					(pts
						(arc
							(start -0.1778 0.2794)
							(mid -0.249642 0.249642)
							(end -0.2794 0.1778)
						)
						(arc
							(start -0.2794 -0.1778)
							(mid -0.249642 -0.249642)
							(end -0.1778 -0.2794)
						)
						(arc
							(start 0.1778 -0.2794)
							(mid 0.249642 -0.249642)
							(end 0.2794 -0.1778)
						)
						(arc
							(start 0.2794 0.1778)
							(mid 0.249642 0.249642)
							(end 0.1778 0.2794)
						)
					)
					(width 0)
					(fill yes)
				)
			)
		)
	)
	(footprint ""
		(layer "B.Cu")
		(at 249.301 -286.2072 90)
		(property "Reference" "C694"
			(at 0 0 90)
			(layer "B.SilkS")
			(hide yes)
			(effects
				(font
					(size 1.27 1.27)
				)
				(justify mirror)
			)
		)
		(property "Value" "SC1U25V3KX-GP"
			(at 0 -2.8194 90)
			(unlocked yes)
			(layer "B.Fab")
			(hide yes)
			(effects
				(font
					(size 1.016 1.016)
					(thickness 0.1524)
				)
				(justify mirror)
			)
		)
		(property "Device Type" "C603H36"
			(at 0 -4.3434 90)
			(unlocked yes)
			(layer "B.Fab")
			(hide yes)
			(effects
				(font
					(size 1.016 1.016)
					(thickness 0.1524)
				)
				(justify mirror)
			)
		)
		(duplicate_pad_numbers_are_jumpers no)
		(fp_line
			(start -0.508 0)
			(end 0.508 0)
			(stroke
				(width 0.2032)
				(type default)
			)
			(layer "B.SilkS")
		)
		(fp_rect
			(start 0.5842 1.3335)
			(end -0.5842 -1.3335)
			(stroke
				(width 0)
				(type default)
			)
			(fill no)
			(layer "B.CrtYd")
		)
		(fp_rect
			(start 0.5842 1.3335)
			(end -0.5842 -1.3335)
			(stroke
				(width 0)
				(type default)
			)
			(fill no)
			(layer "B.Fab")
		)
		(pad "1" smd custom
			(at 0 -0.762 270)
			(size 0.2159 0.2159)
			(layers "B.Cu" "B.Mask" "B.Paste")
			(net "P3V3_STBY_SW")
			(options
				(clearance outline)
				(anchor circle)
			)
			(primitives
				(gr_poly
					(pts
						(arc
							(start -0.3302 0.4318)
							(mid -0.402042 0.402042)
							(end -0.4318 0.3302)
						)
						(arc
							(start -0.4318 -0.3302)
							(mid -0.402042 -0.402042)
							(end -0.3302 -0.4318)
						)
						(arc
							(start 0.3302 -0.4318)
							(mid 0.402042 -0.402042)
							(end 0.4318 -0.3302)
						)
						(arc
							(start 0.4318 0.3302)
							(mid 0.402042 0.402042)
							(end 0.3302 0.4318)
						)
					)
					(width 0)
					(fill yes)
				)
			)
		)
		(pad "2" smd custom
			(at 0 0.762 270)
			(size 0.2159 0.2159)
			(layers "B.Cu" "B.Mask" "B.Paste")
			(net "P3V3_STBY_VBST_RR")
			(options
				(clearance outline)
				(anchor circle)
			)
			(primitives
				(gr_poly
					(pts
						(arc
							(start -0.3302 0.4318)
							(mid -0.402042 0.402042)
							(end -0.4318 0.3302)
						)
						(arc
							(start -0.4318 -0.3302)
							(mid -0.402042 -0.402042)
							(end -0.3302 -0.4318)
						)
						(arc
							(start 0.3302 -0.4318)
							(mid 0.402042 -0.402042)
							(end 0.4318 -0.3302)
						)
						(arc
							(start 0.4318 0.3302)
							(mid 0.402042 0.402042)
							(end 0.3302 0.4318)
						)
					)
					(width 0)
					(fill yes)
				)
			)
		)
	)
	(footprint ""
		(layer "B.Cu")
		(at 24.4602 -229.6922 90)
		(property "Reference" "R1109"
			(at 0 0 90)
			(layer "B.SilkS")
			(hide yes)
			(effects
				(font
					(size 1.27 1.27)
				)
				(justify mirror)
			)
		)
		(property "Value" "71K5R2F-GP"
			(at -0.064008 -3.993896 90)
			(unlocked yes)
			(layer "B.Fab")
			(hide yes)
			(effects
				(font
					(size 1.016 1.016)
					(thickness 0.1524)
				)
				(justify mirror)
			)
		)
		(property "Device Type" "R402H16"
			(at -0.064008 -5.517896 90)
			(unlocked yes)
			(layer "B.Fab")
			(hide yes)
			(effects
				(font
					(size 1.016 1.016)
					(thickness 0.1524)
				)
				(justify mirror)
			)
		)
		(duplicate_pad_numbers_are_jumpers no)
		(fp_line
			(start 0.508 -0.9398)
			(end 0.508 0.9398)
			(stroke
				(width 0.1524)
				(type default)
			)
			(layer "B.SilkS")
		)
		(fp_line
			(start -0.508 -0.9398)
			(end 0.508 -0.9398)
			(stroke
				(width 0.1524)
				(type default)
			)
			(layer "B.SilkS")
		)
		(fp_rect
			(start 0.508 0.9398)
			(end -0.508 -0.9398)
			(stroke
				(width 0)
				(type default)
			)
			(fill no)
			(layer "B.CrtYd")
		)
		(fp_rect
			(start 0.508 0.9398)
			(end -0.508 -0.9398)
			(stroke
				(width 0)
				(type default)
			)
			(fill no)
			(layer "B.Fab")
		)
		(pad "1" smd custom
			(at 0 -0.4445 270)
			(size 0.1397 0.1397)
			(layers "B.Cu" "B.Mask" "B.Paste")
			(net "P5V_B_1_VFB")
			(options
				(clearance outline)
				(anchor circle)
			)
			(primitives
				(gr_poly
					(pts
						(arc
							(start -0.1778 0.2794)
							(mid -0.249642 0.249642)
							(end -0.2794 0.1778)
						)
						(arc
							(start -0.2794 -0.1778)
							(mid -0.249642 -0.249642)
							(end -0.1778 -0.2794)
						)
						(arc
							(start 0.1778 -0.2794)
							(mid 0.249642 -0.249642)
							(end 0.2794 -0.1778)
						)
						(arc
							(start 0.2794 0.1778)
							(mid 0.249642 0.249642)
							(end 0.1778 0.2794)
						)
					)
					(width 0)
					(fill yes)
				)
			)
		)
		(pad "2" smd custom
			(at 0 0.4445 270)
			(size 0.1397 0.1397)
			(layers "B.Cu" "B.Mask" "B.Paste")
			(net "P5V_B_1_VFB_R")
			(options
				(clearance outline)
				(anchor circle)
			)
			(primitives
				(gr_poly
					(pts
						(arc
							(start -0.1778 0.2794)
							(mid -0.249642 0.249642)
							(end -0.2794 0.1778)
						)
						(arc
							(start -0.2794 -0.1778)
							(mid -0.249642 -0.249642)
							(end -0.1778 -0.2794)
						)
						(arc
							(start 0.1778 -0.2794)
							(mid 0.249642 -0.249642)
							(end 0.2794 -0.1778)
						)
						(arc
							(start 0.2794 0.1778)
							(mid 0.249642 0.249642)
							(end 0.1778 0.2794)
						)
					)
					(width 0)
					(fill yes)
				)
			)
		)
	)
	(footprint ""
		(layer "B.Cu")
		(at 167.7162 -370.205 90)
		(property "Reference" "R1032"
			(at 0 0 90)
			(layer "B.SilkS")
			(hide yes)
			(effects
				(font
					(size 1.27 1.27)
				)
				(justify mirror)
			)
		)
		(property "Value" "10R2F-L-GP"
			(at -0.064008 -3.993896 90)
			(unlocked yes)
			(layer "B.Fab")
			(hide yes)
			(effects
				(font
					(size 1.016 1.016)
					(thickness 0.1524)
				)
				(justify mirror)
			)
		)
		(property "Device Type" "R402H14"
			(at -0.064008 -5.517896 90)
			(unlocked yes)
			(layer "B.Fab")
			(hide yes)
			(effects
				(font
					(size 1.016 1.016)
					(thickness 0.1524)
				)
				(justify mirror)
			)
		)
		(duplicate_pad_numbers_are_jumpers no)
		(fp_line
			(start 0.508 -0.9398)
			(end 0.508 0.9398)
			(stroke
				(width 0.1524)
				(type default)
			)
			(layer "B.SilkS")
		)
		(fp_line
			(start -0.508 -0.9398)
			(end 0.508 -0.9398)
			(stroke
				(width 0.1524)
				(type default)
			)
			(layer "B.SilkS")
		)
		(fp_rect
			(start 0.508 0.9398)
			(end -0.508 -0.9398)
			(stroke
				(width 0)
				(type default)
			)
			(fill no)
			(layer "B.CrtYd")
		)
		(fp_rect
			(start 0.508 0.9398)
			(end -0.508 -0.9398)
			(stroke
				(width 0)
				(type default)
			)
			(fill no)
			(layer "B.Fab")
		)
		(pad "1" smd custom
			(at 0 -0.4445 270)
			(size 0.1397 0.1397)
			(layers "B.Cu" "B.Mask" "B.Paste")
			(net "MB0_CM_SENSE_R1_N")
			(options
				(clearance outline)
				(anchor circle)
			)
			(primitives
				(gr_poly
					(pts
						(arc
							(start -0.1778 0.2794)
							(mid -0.249642 0.249642)
							(end -0.2794 0.1778)
						)
						(arc
							(start -0.2794 -0.1778)
							(mid -0.249642 -0.249642)
							(end -0.1778 -0.2794)
						)
						(arc
							(start 0.1778 -0.2794)
							(mid 0.249642 -0.249642)
							(end 0.2794 -0.1778)
						)
						(arc
							(start 0.2794 0.1778)
							(mid 0.249642 0.249642)
							(end 0.1778 0.2794)
						)
					)
					(width 0)
					(fill yes)
				)
			)
		)
		(pad "2" smd custom
			(at 0 0.4445 270)
			(size 0.1397 0.1397)
			(layers "B.Cu" "B.Mask" "B.Paste")
			(net "MB0_HS_SENSE_N")
			(options
				(clearance outline)
				(anchor circle)
			)
			(primitives
				(gr_poly
					(pts
						(arc
							(start -0.1778 0.2794)
							(mid -0.249642 0.249642)
							(end -0.2794 0.1778)
						)
						(arc
							(start -0.2794 -0.1778)
							(mid -0.249642 -0.249642)
							(end -0.1778 -0.2794)
						)
						(arc
							(start 0.1778 -0.2794)
							(mid 0.249642 -0.249642)
							(end 0.2794 -0.1778)
						)
						(arc
							(start 0.2794 0.1778)
							(mid 0.249642 0.249642)
							(end 0.1778 0.2794)
						)
					)
					(width 0)
					(fill yes)
				)
			)
		)
	)
	(footprint ""
		(layer "B.Cu")
		(at 441.162186 -120.321578 90)
		(property "Reference" "C684"
			(at 0 0 90)
			(layer "B.SilkS")
			(hide yes)
			(effects
				(font
					(size 1.27 1.27)
				)
				(justify mirror)
			)
		)
		(property "Value" "SC68P50V2JN-2-GP"
			(at -1.1811 -2.7051 90)
			(unlocked yes)
			(layer "B.Fab")
			(hide yes)
			(effects
				(font
					(size 1.016 1.016)
					(thickness 0.1524)
				)
				(justify mirror)
			)
		)
		(property "Device Type" "C402H22"
			(at -1.1811 -4.2291 90)
			(unlocked yes)
			(layer "B.Fab")
			(hide yes)
			(effects
				(font
					(size 1.016 1.016)
					(thickness 0.1524)
				)
				(justify mirror)
			)
		)
		(duplicate_pad_numbers_are_jumpers no)
		(fp_rect
			(start 0.4318 0.9525)
			(end -0.4318 -0.9525)
			(stroke
				(width 0)
				(type default)
			)
			(fill no)
			(layer "B.CrtYd")
		)
		(fp_rect
			(start 0.4318 0.9525)
			(end -0.4318 -0.9525)
			(stroke
				(width 0)
				(type default)
			)
			(fill no)
			(layer "B.Fab")
		)
		(pad "1" smd custom
			(at 0 -0.4445 270)
			(size 0.1524 0.1524)
			(layers "B.Cu" "B.Mask" "B.Paste")
			(net "P5V_B_4_VFB")
			(options
				(clearance outline)
				(anchor circle)
			)
			(primitives
				(gr_poly
					(pts
						(arc
							(start 0.3048 0.2032)
							(mid 0.275042 0.275042)
							(end 0.2032 0.3048)
						)
						(arc
							(start -0.2032 0.3048)
							(mid -0.275042 0.275042)
							(end -0.3048 0.2032)
						)
						(arc
							(start -0.3048 -0.2032)
							(mid -0.275042 -0.275042)
							(end -0.2032 -0.3048)
						)
						(arc
							(start 0.2032 -0.3048)
							(mid 0.275042 -0.275042)
							(end 0.3048 -0.2032)
						)
					)
					(width 0)
					(fill yes)
				)
			)
		)
		(pad "2" smd custom
			(at 0 0.4445 270)
			(size 0.1524 0.1524)
			(layers "B.Cu" "B.Mask" "B.Paste")
			(net "P5V_B_4_VFB_R")
			(options
				(clearance outline)
				(anchor circle)
			)
			(primitives
				(gr_poly
					(pts
						(arc
							(start 0.3048 0.2032)
							(mid 0.275042 0.275042)
							(end 0.2032 0.3048)
						)
						(arc
							(start -0.2032 0.3048)
							(mid -0.275042 0.275042)
							(end -0.3048 0.2032)
						)
						(arc
							(start -0.3048 -0.2032)
							(mid -0.275042 -0.275042)
							(end -0.2032 -0.3048)
						)
						(arc
							(start 0.2032 -0.3048)
							(mid 0.275042 -0.275042)
							(end 0.3048 -0.2032)
						)
					)
					(width 0)
					(fill yes)
				)
			)
		)
	)
	(footprint ""
		(layer "B.Cu")
		(at 201.836274 -333.39659 90)
		(property "Reference" "Q194"
			(at 0 0 90)
			(layer "B.SilkS")
			(hide yes)
			(effects
				(font
					(size 1.27 1.27)
				)
				(justify mirror)
			)
		)
		(property "Value" "IRFH8201TRPBF-GP"
			(at 4.2164 -4.3688 90)
			(unlocked yes)
			(layer "B.Fab")
			(hide yes)
			(effects
				(font
					(size 1.016 1.016)
					(thickness 0.1524)
				)
				(justify mirror)
			)
		)
		(property "Device Type" "PPAK-5PH42"
			(at 4.2164 -5.8928 90)
			(unlocked yes)
			(layer "B.Fab")
			(hide yes)
			(effects
				(font
					(size 1.016 1.016)
					(thickness 0.1524)
				)
				(justify mirror)
			)
		)
		(duplicate_pad_numbers_are_jumpers no)
		(fp_line
			(start 2.8956 -2.794)
			(end -2.8956 -2.794)
			(stroke
				(width 0.1524)
				(type default)
			)
			(layer "B.SilkS")
		)
		(fp_line
			(start -2.8956 -2.794)
			(end -2.8956 4.826)
			(stroke
				(width 0.1524)
				(type default)
			)
			(layer "B.SilkS")
		)
		(fp_line
			(start 2.8956 4.826)
			(end 2.8956 -2.794)
			(stroke
				(width 0.1524)
				(type default)
			)
			(layer "B.SilkS")
		)
		(fp_line
			(start -2.8956 4.826)
			(end 2.8956 4.826)
			(stroke
				(width 0.1524)
				(type default)
			)
			(layer "B.SilkS")
		)
		(fp_line
			(start 3.0353 4.9276)
			(end 3.0353 3.9624)
			(stroke
				(width 0.3302)
				(type default)
			)
			(layer "B.SilkS")
		)
		(fp_line
			(start 1.9431 4.9276)
			(end 3.0353 4.9276)
			(stroke
				(width 0.3302)
				(type default)
			)
			(layer "B.SilkS")
		)
		(fp_poly
			(pts
				(xy 2.3622 5.334) (xy 1.4986 5.334) (xy 1.9304 4.9022)
			)
			(stroke
				(width 0)
				(type default)
			)
			(fill yes)
			(layer "B.SilkS")
		)
		(fp_poly
			(pts
				(xy 2.6416 -0.3556) (xy 0.3556 -0.3556) (xy 0.3556 -2.54) (xy 2.6416 -2.54)
			)
			(stroke
				(width 0)
				(type default)
			)
			(fill yes)
			(layer "B.Paste")
		)
		(fp_poly
			(pts
				(xy -0.3556 -0.3556) (xy -2.6416 -0.3556) (xy -2.6416 -2.54) (xy -0.3556 -2.54)
			)
			(stroke
				(width 0)
				(type default)
			)
			(fill yes)
			(layer "B.Paste")
		)
		(fp_poly
			(pts
				(xy 2.6416 2.54) (xy 0.3556 2.54) (xy 0.3556 0.3556) (xy 2.6416 0.3556)
			)
			(stroke
				(width 0)
				(type default)
			)
			(fill yes)
			(layer "B.Paste")
		)
		(fp_poly
			(pts
				(xy -0.3556 2.54) (xy -2.6416 2.54) (xy -2.6416 0.3556) (xy -0.3556 0.3556)
			)
			(stroke
				(width 0)
				(type default)
			)
			(fill yes)
			(layer "B.Paste")
		)
		(fp_rect
			(start 2.5781 3.9878)
			(end -2.5781 -2.1082)
			(stroke
				(width 0)
				(type default)
			)
			(fill no)
			(layer "B.CrtYd")
		)
		(fp_poly
			(pts
				(xy 3.1496 5.08) (xy 3.1496 -3.048) (xy -3.1496 -3.048) (xy -3.1496 3.9751) (xy -2.5781 3.9751)
				(xy -2.5781 -2.1082) (xy 2.5781 -2.1082) (xy 2.5781 3.9878) (xy -3.1496 3.9878) (xy -3.1496 5.08)
			)
			(stroke
				(width 0)
				(type default)
			)
			(fill no)
			(layer "B.CrtYd")
		)
		(fp_rect
			(start 3.1496 5.08)
			(end -3.1496 -3.048)
			(stroke
				(width 0)
				(type default)
			)
			(fill no)
			(layer "B.Fab")
		)
		(pad "1" smd rect
			(at 1.905 3.81 270)
			(size 0.762 1.524)
			(layers "B.Cu" "B.Mask" "B.Paste")
			(net "P12V_IN")
		)
		(pad "2" smd rect
			(at 0.635 3.81 270)
			(size 0.762 1.524)
			(layers "B.Cu" "B.Mask" "B.Paste")
			(net "P12V_IN")
		)
		(pad "3" smd rect
			(at -0.635 3.81 270)
			(size 0.762 1.524)
			(layers "B.Cu" "B.Mask" "B.Paste")
			(net "P12V_IN")
		)
		(pad "4" smd rect
			(at -1.905 3.81 270)
			(size 0.762 1.524)
			(layers "B.Cu" "B.Mask" "B.Paste")
			(net "MB0_12V_CTRL_GATE1")
		)
		(pad "5" smd rect
			(at 0 0 270)
			(size 5.2832 5.08)
			(layers "B.Cu" "B.Mask" "B.Paste")
			(net "MB0_P12V_IN_R")
		)
		(pad "6" smd rect
			(at -0.635 -2.032 270)
			(size 0.0254 0.0254)
			(layers "B.Cu" "B.Mask" "B.Paste")
			(net "MB0_P12V_IN_R")
		)
		(pad "7" smd rect
			(at 0.635 -2.032 270)
			(size 0.0254 0.0254)
			(layers "B.Cu" "B.Mask" "B.Paste")
			(net "MB0_P12V_IN_R")
		)
		(pad "8" smd rect
			(at 1.905 -2.032 270)
			(size 0.0254 0.0254)
			(layers "B.Cu" "B.Mask" "B.Paste")
			(net "MB0_P12V_IN_R")
		)
	)
)
